# T6G (Grand Teton) — schematic netlist excerpt (pin names and nets, part order shuffled) for the footprints in the layout excerpt that follows; sources: Cadence DE-HDL packaged netlist, KiCad conversion of 04192023_DAF0TMB3IC0_F0TG_MB_C_brd_V02_OCP.brd

R606  Q_RES  0 5% CHIP  pkg 0402LF  page 77 : A = SPI_CPU0_LVC3_D2 ; B = SPI_CPU0_LVC3_SCM_D2
PC111  Q_CAP  22UF 16V 20% X6S  pkg C0805  page 209 : A = SW_P12V_AUX_PVDD18_S5_P0_FLT ; B = GND
C47  Q_CAP_DIFFBUS  DIFF BUS_0.22UF 6.3V 20% X6S  pkg C0201  page 65 : \1\ = P5E_CPU0_G3_TX_C_DP<6> ; \2\ = P5E_CPU0_G3_TX_DP<6>
H100  HOLE  EMPTY  pkg TH  page 230 : \1\ = GND
C6502  Q_CAP_DIFFBUS  DIFF BUS_0.22UF 6.3V 20% X6S  pkg C0201  page 275 : \1\ = P5E_CPU0_P0_TX_BUF_C_DN<0> ; \2\ = P5E_CPU0_P0_TX_BUF_DN<0>

(kicad_pcb
	(version 20260206)
	(generator "pcbnew")
	(generator_version "10.0")
	(general
		(thickness 1.6)
		(legacy_teardrops no)
	)
	(paper "A4")
	(title_block
		(title "04192023_DAF0TMB3IC0_F0TG_MB_C_brd_V02_OCP.brd")
		(comment 1 "Grand Teton / footprints 875-879 of 8354")
	)
	(layers
		(0 "F.Cu" signal "TOP")
		(4 "In1.Cu" signal "GND")
		(6 "In2.Cu" signal "IN1")
		(8 "In3.Cu" signal "GND1")
		(10 "In4.Cu" signal "IN2")
		(12 "In5.Cu" signal "GND2")
		(14 "In6.Cu" signal "IN3")
		(16 "In7.Cu" signal "GND3")
		(18 "In8.Cu" signal "VCC")
		(20 "In9.Cu" signal "VCC1")
		(22 "In10.Cu" signal "GND4")
		(24 "In11.Cu" signal "IN4")
		(26 "In12.Cu" signal "GND5")
		(28 "In13.Cu" signal "IN5")
		(30 "In14.Cu" signal "GND6")
		(32 "In15.Cu" signal "IN6")
		(34 "In16.Cu" signal "GND7")
		(2 "B.Cu" signal "BOTTOM")
		(9 "F.Adhes" user "F.Adhesive")
		(11 "B.Adhes" user "B.Adhesive")
		(13 "F.Paste" user "Package Geometry/Pastemask Top")
		(15 "B.Paste" user "Package Geometry/Pastemask Bottom")
		(5 "F.SilkS" user "Ref Des/Silkscreen Top")
		(7 "B.SilkS" user "Ref Des/Silkscreen Bottom")
		(1 "F.Mask" user "Board Geometry/Soldermask Top")
		(3 "B.Mask" user "Board Geometry/Soldermask Bottom")
		(17 "Dwgs.User" user "User.Drawings")
		(19 "Cmts.User" user "User.Comments")
		(21 "Eco1.User" user "User.Eco1")
		(23 "Eco2.User" user "User.Eco2")
		(25 "Edge.Cuts" user "Board Geometry/Outline")
		(27 "Margin" user)
		(31 "F.CrtYd" user "Package Geometry/Place Bound Top")
		(29 "B.CrtYd" user "Package Geometry/Place Bound Bottom")
		(35 "F.Fab" user "Ref Des/Assembly Top")
		(33 "B.Fab" user "Ref Des/Assembly Bottom")
	)
	(footprint ""
		(layer "F.Cu")
		(at 416.373564 -17.624298 90)
		(property "Reference" "C47"
			(at 0 0 90)
			(layer "F.SilkS")
			(hide yes)
			(effects
				(font
					(size 1.27 1.27)
				)
			)
		)
		(property "Value" ""
			(at 0 0 90)
			(layer "F.Fab")
			(effects
				(font
					(size 1.27 1.27)
				)
			)
		)
		(duplicate_pad_numbers_are_jumpers no)
		(fp_line
			(start 0.299974 -0.150114)
			(end 0.299974 0.150114)
			(stroke
				(width 0.1)
				(type default)
			)
			(layer "F.Fab")
		)
		(fp_line
			(start -0.299974 -0.150114)
			(end 0.299974 -0.150114)
			(stroke
				(width 0.1)
				(type default)
			)
			(layer "F.Fab")
		)
		(fp_line
			(start 0.299974 0.150114)
			(end -0.299974 0.150114)
			(stroke
				(width 0.1)
				(type default)
			)
			(layer "F.Fab")
		)
		(fp_line
			(start -0.299974 0.150114)
			(end -0.299974 -0.150114)
			(stroke
				(width 0.1)
				(type default)
			)
			(layer "F.Fab")
		)
		(pad "1" smd rect
			(at -0.2667 0 90)
			(size 0.3048 0.381)
			(layers "F.Cu" "F.Mask" "F.Paste")
			(net "P5E_CPU0_G3_TX_C_DP<6>")
		)
		(pad "2" smd rect
			(at 0.2667 0 90)
			(size 0.3048 0.381)
			(layers "F.Cu" "F.Mask" "F.Paste")
			(net "P5E_CPU0_G3_TX_DP<6>")
		)
	)
	(footprint ""
		(layer "F.Cu")
		(at 336.172556 -135.50265)
		(property "Reference" "PC111"
			(at 0 0 0)
			(layer "F.SilkS")
			(hide yes)
			(effects
				(font
					(size 1.27 1.27)
				)
			)
		)
		(property "Value" ""
			(at 0 0 0)
			(layer "F.Fab")
			(effects
				(font
					(size 1.27 1.27)
				)
			)
		)
		(duplicate_pad_numbers_are_jumpers no)
		(fp_line
			(start -1.524 -0.762)
			(end 1.524 -0.762)
			(stroke
				(width 0.1524)
				(type default)
			)
			(layer "F.SilkS")
		)
		(fp_line
			(start -1.524 0.762)
			(end -1.524 -0.762)
			(stroke
				(width 0.1524)
				(type default)
			)
			(layer "F.SilkS")
		)
		(fp_line
			(start 1.524 -0.762)
			(end 1.524 0.762)
			(stroke
				(width 0.1524)
				(type default)
			)
			(layer "F.SilkS")
		)
		(fp_line
			(start 1.524 0.762)
			(end -1.524 0.762)
			(stroke
				(width 0.1524)
				(type default)
			)
			(layer "F.SilkS")
		)
		(fp_line
			(start -1.1049 -0.724916)
			(end -1.1049 0.724916)
			(stroke
				(width 0.1)
				(type default)
			)
			(layer "F.Fab")
		)
		(fp_line
			(start -1.1049 0.724916)
			(end 1.1049 0.724916)
			(stroke
				(width 0.1)
				(type default)
			)
			(layer "F.Fab")
		)
		(fp_line
			(start 1.1049 -0.724916)
			(end -1.1049 -0.724916)
			(stroke
				(width 0.1)
				(type default)
			)
			(layer "F.Fab")
		)
		(fp_line
			(start 1.1049 0.724916)
			(end 1.1049 -0.724916)
			(stroke
				(width 0.1)
				(type default)
			)
			(layer "F.Fab")
		)
		(pad "1" smd rect
			(at -0.889 0 180)
			(size 1.016 1.27)
			(layers "F.Cu" "F.Mask" "F.Paste")
			(net "SW_P12V_AUX_PVDD18_S5_P0_FLT")
		)
		(pad "2" smd rect
			(at 0.889 0 180)
			(size 1.016 1.27)
			(layers "F.Cu" "F.Mask" "F.Paste")
			(net "GND")
		)
	)
	(footprint ""
		(layer "F.Cu")
		(at 303.768506 -416.899344 -90)
		(property "Reference" "C6502"
			(at 0 0 270)
			(layer "F.SilkS")
			(hide yes)
			(effects
				(font
					(size 1.27 1.27)
				)
			)
		)
		(property "Value" ""
			(at 0 0 270)
			(layer "F.Fab")
			(effects
				(font
					(size 1.27 1.27)
				)
			)
		)
		(duplicate_pad_numbers_are_jumpers no)
		(fp_line
			(start -0.299974 0.150114)
			(end -0.299974 -0.150114)
			(stroke
				(width 0.1)
				(type default)
			)
			(layer "F.Fab")
		)
		(fp_line
			(start 0.299974 0.150114)
			(end -0.299974 0.150114)
			(stroke
				(width 0.1)
				(type default)
			)
			(layer "F.Fab")
		)
		(fp_line
			(start -0.299974 -0.150114)
			(end 0.299974 -0.150114)
			(stroke
				(width 0.1)
				(type default)
			)
			(layer "F.Fab")
		)
		(fp_line
			(start 0.299974 -0.150114)
			(end 0.299974 0.150114)
			(stroke
				(width 0.1)
				(type default)
			)
			(layer "F.Fab")
		)
		(pad "1" smd rect
			(at -0.2667 0 270)
			(size 0.3048 0.381)
			(layers "F.Cu" "F.Mask" "F.Paste")
			(net "P5E_CPU0_P0_TX_BUF_C_DN<0>")
		)
		(pad "2" smd rect
			(at 0.2667 0 270)
			(size 0.3048 0.381)
			(layers "F.Cu" "F.Mask" "F.Paste")
			(net "P5E_CPU0_P0_TX_BUF_DN<0>")
		)
	)
	(footprint ""
		(layer "F.Cu")
		(at 257.501644 -139.718796 180)
		(property "Reference" "R606"
			(at 0 0 180)
			(layer "F.SilkS")
			(hide yes)
			(effects
				(font
					(size 1.27 1.27)
				)
			)
		)
		(property "Value" ""
			(at 0 0 180)
			(layer "F.Fab")
			(effects
				(font
					(size 1.27 1.27)
				)
			)
		)
		(duplicate_pad_numbers_are_jumpers no)
		(fp_line
			(start 0.7874 0.4064)
			(end -0.7874 0.4064)
			(stroke
				(width 0.1524)
				(type default)
			)
			(layer "F.SilkS")
		)
		(fp_line
			(start 0.7874 -0.4064)
			(end 0.7874 0.4064)
			(stroke
				(width 0.1524)
				(type default)
			)
			(layer "F.SilkS")
		)
		(fp_line
			(start -0.7874 0.4064)
			(end -0.7874 -0.4064)
			(stroke
				(width 0.1524)
				(type default)
			)
			(layer "F.SilkS")
		)
		(fp_line
			(start -0.7874 -0.4064)
			(end 0.7874 -0.4064)
			(stroke
				(width 0.1524)
				(type default)
			)
			(layer "F.SilkS")
		)
		(fp_line
			(start 0.67945 0.3048)
			(end 0.120396 0.3048)
			(stroke
				(width 0.1)
				(type default)
			)
			(layer "F.Fab")
		)
		(fp_line
			(start 0.67945 -0.3048)
			(end 0.67945 0.3048)
			(stroke
				(width 0.1)
				(type default)
			)
			(layer "F.Fab")
		)
		(fp_line
			(start 0.12065 -0.2794)
			(end 0.12065 -0.3048)
			(stroke
				(width 0.1)
				(type default)
			)
			(layer "F.Fab")
		)
		(fp_line
			(start 0.12065 -0.3048)
			(end 0.67945 -0.3048)
			(stroke
				(width 0.1)
				(type default)
			)
			(layer "F.Fab")
		)
		(fp_line
			(start 0.120396 0.3048)
			(end 0.120396 0.2794)
			(stroke
				(width 0.1)
				(type default)
			)
			(layer "F.Fab")
		)
		(fp_line
			(start 0.120396 0.2794)
			(end -0.12065 0.2794)
			(stroke
				(width 0.1)
				(type default)
			)
			(layer "F.Fab")
		)
		(fp_line
			(start -0.12065 0.3048)
			(end -0.67945 0.3048)
			(stroke
				(width 0.1)
				(type default)
			)
			(layer "F.Fab")
		)
		(fp_line
			(start -0.12065 0.2794)
			(end -0.12065 0.3048)
			(stroke
				(width 0.1)
				(type default)
			)
			(layer "F.Fab")
		)
		(fp_line
			(start -0.12065 -0.2794)
			(end 0.12065 -0.2794)
			(stroke
				(width 0.1)
				(type default)
			)
			(layer "F.Fab")
		)
		(fp_line
			(start -0.12065 -0.305054)
			(end -0.12065 -0.2794)
			(stroke
				(width 0.1)
				(type default)
			)
			(layer "F.Fab")
		)
		(fp_line
			(start -0.67945 0.3048)
			(end -0.67945 -0.305054)
			(stroke
				(width 0.1)
				(type default)
			)
			(layer "F.Fab")
		)
		(fp_line
			(start -0.67945 -0.305054)
			(end -0.12065 -0.305054)
			(stroke
				(width 0.1)
				(type default)
			)
			(layer "F.Fab")
		)
		(pad "1" smd circle
			(at -0.40005 0 180)
			(size 0 0)
			(layers "F.Cu" "F.Mask" "F.Paste")
			(net "SPI_CPU0_LVC3_D2")
		)
		(pad "2" smd circle
			(at 0.40005 0 180)
			(size 0 0)
			(layers "F.Cu" "F.Mask" "F.Paste")
			(net "SPI_CPU0_LVC3_SCM_D2")
		)
	)
	(footprint ""
		(layer "F.Cu")
		(at 236.649768 -272.50009)
		(property "Reference" "H100"
			(at -4.274566 -5.764276 0)
			(unlocked yes)
			(layer "F.SilkS")
			(effects
				(font
					(size 0.7874 0.5842)
					(thickness 0.1524)
				)
				(justify left)
			)
		)
		(property "Value" ""
			(at 0 0 0)
			(layer "F.Fab")
			(effects
				(font
					(size 1.27 1.27)
				)
			)
		)
		(duplicate_pad_numbers_are_jumpers no)
		(pad "1" thru_hole circle
			(at 0 0)
			(size 10.0076 10.0076)
			(drill 5.6134)
			(layers "*.Cu" "*.Mask")
			(remove_unused_layers no)
			(net "GND")
			(clearance -1.9431)
		)
	)
)
